(kicad_pcb
	(version 20260206)
	(generator "pcbnew")
	(generator_version "10.0")
	(general
		(thickness 1.6)
		(legacy_teardrops no)
	)
	(paper "A4")
	(title_block
		(title "04192023_DAF0TMB3IC0_F0TG_MB_C_brd_V02_OCP.brd")
		(comment 1 "Grand Teton / footprints 4919-4921 of 8354")
	)
	(layers
		(0 "F.Cu" signal "TOP")
		(4 "In1.Cu" signal "GND")
		(6 "In2.Cu" signal "IN1")
		(8 "In3.Cu" signal "GND1")
		(10 "In4.Cu" signal "IN2")
		(12 "In5.Cu" signal "GND2")
		(14 "In6.Cu" signal "IN3")
		(16 "In7.Cu" signal "GND3")
		(18 "In8.Cu" signal "VCC")
		(20 "In9.Cu" signal "VCC1")
		(22 "In10.Cu" signal "GND4")
		(24 "In11.Cu" signal "IN4")
		(26 "In12.Cu" signal "GND5")
		(28 "In13.Cu" signal "IN5")
		(30 "In14.Cu" signal "GND6")
		(32 "In15.Cu" signal "IN6")
		(34 "In16.Cu" signal "GND7")
		(2 "B.Cu" signal "BOTTOM")
		(9 "F.Adhes" user "F.Adhesive")
		(11 "B.Adhes" user "B.Adhesive")
		(13 "F.Paste" user "Package Geometry/Pastemask Top")
		(15 "B.Paste" user "Package Geometry/Pastemask Bottom")
		(5 "F.SilkS" user "Ref Des/Silkscreen Top")
		(7 "B.SilkS" user "Ref Des/Silkscreen Bottom")
		(1 "F.Mask" user "Board Geometry/Soldermask Top")
		(3 "B.Mask" user "Board Geometry/Soldermask Bottom")
		(17 "Dwgs.User" user "User.Drawings")
		(19 "Cmts.User" user "User.Comments")
		(21 "Eco1.User" user "User.Eco1")
		(23 "Eco2.User" user "User.Eco2")
		(25 "Edge.Cuts" user "Board Geometry/Outline")
		(27 "Margin" user)
		(31 "F.CrtYd" user "Package Geometry/Place Bound Top")
		(29 "B.CrtYd" user "Package Geometry/Place Bound Bottom")
		(35 "F.Fab" user "Ref Des/Assembly Top")
		(33 "B.Fab" user "Ref Des/Assembly Bottom")
	)
	(footprint ""
		(layer "F.Cu")
		(at 279.670256 -430.791366 180)
		(property "Reference" "R4264"
			(at 0 0 180)
			(layer "F.SilkS")
			(hide yes)
			(effects
				(font
					(size 1.27 1.27)
				)
			)
		)
		(property "Value" ""
			(at 0 0 180)
			(layer "F.Fab")
			(effects
				(font
					(size 1.27 1.27)
				)
			)
		)
		(duplicate_pad_numbers_are_jumpers no)
		(fp_line
			(start 0.7874 0.4064)
			(end -0.7874 0.4064)
			(stroke
				(width 0.1524)
				(type default)
			)
			(layer "F.SilkS")
		)
		(fp_line
			(start 0.7874 -0.4064)
			(end 0.7874 0.4064)
			(stroke
				(width 0.1524)
				(type default)
			)
			(layer "F.SilkS")
		)
		(fp_line
			(start -0.7874 0.4064)
			(end -0.7874 -0.4064)
			(stroke
				(width 0.1524)
				(type default)
			)
			(layer "F.SilkS")
		)
		(fp_line
			(start -0.7874 -0.4064)
			(end 0.7874 -0.4064)
			(stroke
				(width 0.1524)
				(type default)
			)
			(layer "F.SilkS")
		)
		(fp_line
			(start 0.67945 0.3048)
			(end 0.120396 0.3048)
			(stroke
				(width 0.1)
				(type default)
			)
			(layer "F.Fab")
		)
		(fp_line
			(start 0.67945 -0.3048)
			(end 0.67945 0.3048)
			(stroke
				(width 0.1)
				(type default)
			)
			(layer "F.Fab")
		)
		(fp_line
			(start 0.12065 -0.2794)
			(end 0.12065 -0.3048)
			(stroke
				(width 0.1)
				(type default)
			)
			(layer "F.Fab")
		)
		(fp_line
			(start 0.12065 -0.3048)
			(end 0.67945 -0.3048)
			(stroke
				(width 0.1)
				(type default)
			)
			(layer "F.Fab")
		)
		(fp_line
			(start 0.120396 0.3048)
			(end 0.120396 0.2794)
			(stroke
				(width 0.1)
				(type default)
			)
			(layer "F.Fab")
		)
		(fp_line
			(start 0.120396 0.2794)
			(end -0.12065 0.2794)
			(stroke
				(width 0.1)
				(type default)
			)
			(layer "F.Fab")
		)
		(fp_line
			(start -0.12065 0.3048)
			(end -0.67945 0.3048)
			(stroke
				(width 0.1)
				(type default)
			)
			(layer "F.Fab")
		)
		(fp_line
			(start -0.12065 0.2794)
			(end -0.12065 0.3048)
			(stroke
				(width 0.1)
				(type default)
			)
			(layer "F.Fab")
		)
		(fp_line
			(start -0.12065 -0.2794)
			(end 0.12065 -0.2794)
			(stroke
				(width 0.1)
				(type default)
			)
			(layer "F.Fab")
		)
		(fp_line
			(start -0.12065 -0.305054)
			(end -0.12065 -0.2794)
			(stroke
				(width 0.1)
				(type default)
			)
			(layer "F.Fab")
		)
		(fp_line
			(start -0.67945 0.3048)
			(end -0.67945 -0.305054)
			(stroke
				(width 0.1)
				(type default)
			)
			(layer "F.Fab")
		)
		(fp_line
			(start -0.67945 -0.305054)
			(end -0.12065 -0.305054)
			(stroke
				(width 0.1)
				(type default)
			)
			(layer "F.Fab")
		)
		(pad "1" smd circle
			(at -0.40005 0 180)
			(size 0 0)
			(layers "F.Cu" "F.Mask" "F.Paste")
			(net "P3V3_AUX")
		)
		(pad "2" smd circle
			(at 0.40005 0 180)
			(size 0 0)
			(layers "F.Cu" "F.Mask" "F.Paste")
			(net "PWRGD_P3V3_AUX_PDB_BUF_R")
		)
	)
	(footprint ""
		(layer "F.Cu")
		(at 308.420516 -433.942744 -90)
		(property "Reference" "R3430"
			(at 0 0 270)
			(layer "F.SilkS")
			(hide yes)
			(effects
				(font
					(size 1.27 1.27)
				)
			)
		)
		(property "Value" ""
			(at 0 0 270)
			(layer "F.Fab")
			(effects
				(font
					(size 1.27 1.27)
				)
			)
		)
		(duplicate_pad_numbers_are_jumpers no)
		(fp_line
			(start -0.7874 0.4064)
			(end -0.7874 -0.4064)
			(stroke
				(width 0.1524)
				(type default)
			)
			(layer "F.SilkS")
		)
		(fp_line
			(start 0.7874 0.4064)
			(end -0.7874 0.4064)
			(stroke
				(width 0.1524)
				(type default)
			)
			(layer "F.SilkS")
		)
		(fp_line
			(start -0.7874 -0.4064)
			(end 0.7874 -0.4064)
			(stroke
				(width 0.1524)
				(type default)
			)
			(layer "F.SilkS")
		)
		(fp_line
			(start 0.7874 -0.4064)
			(end 0.7874 0.4064)
			(stroke
				(width 0.1524)
				(type default)
			)
			(layer "F.SilkS")
		)
		(fp_line
			(start -0.67945 0.3048)
			(end -0.67945 -0.305054)
			(stroke
				(width 0.1)
				(type default)
			)
			(layer "F.Fab")
		)
		(fp_line
			(start -0.12065 0.3048)
			(end -0.67945 0.3048)
			(stroke
				(width 0.1)
				(type default)
			)
			(layer "F.Fab")
		)
		(fp_line
			(start 0.120396 0.3048)
			(end 0.120396 0.2794)
			(stroke
				(width 0.1)
				(type default)
			)
			(layer "F.Fab")
		)
		(fp_line
			(start 0.67945 0.3048)
			(end 0.120396 0.3048)
			(stroke
				(width 0.1)
				(type default)
			)
			(layer "F.Fab")
		)
		(fp_line
			(start -0.12065 0.2794)
			(end -0.12065 0.3048)
			(stroke
				(width 0.1)
				(type default)
			)
			(layer "F.Fab")
		)
		(fp_line
			(start 0.120396 0.2794)
			(end -0.12065 0.2794)
			(stroke
				(width 0.1)
				(type default)
			)
			(layer "F.Fab")
		)
		(fp_line
			(start -0.12065 -0.2794)
			(end 0.12065 -0.2794)
			(stroke
				(width 0.1)
				(type default)
			)
			(layer "F.Fab")
		)
		(fp_line
			(start 0.12065 -0.2794)
			(end 0.12065 -0.3048)
			(stroke
				(width 0.1)
				(type default)
			)
			(layer "F.Fab")
		)
		(fp_line
			(start 0.12065 -0.3048)
			(end 0.67945 -0.3048)
			(stroke
				(width 0.1)
				(type default)
			)
			(layer "F.Fab")
		)
		(fp_line
			(start 0.67945 -0.3048)
			(end 0.67945 0.3048)
			(stroke
				(width 0.1)
				(type default)
			)
			(layer "F.Fab")
		)
		(fp_line
			(start -0.67945 -0.305054)
			(end -0.12065 -0.305054)
			(stroke
				(width 0.1)
				(type default)
			)
			(layer "F.Fab")
		)
		(fp_line
			(start -0.12065 -0.305054)
			(end -0.12065 -0.2794)
			(stroke
				(width 0.1)
				(type default)
			)
			(layer "F.Fab")
		)
		(pad "1" smd circle
			(at -0.40005 0 270)
			(size 0 0)
			(layers "F.Cu" "F.Mask" "F.Paste")
			(net "GPU_FPGA_OVERT_N")
		)
		(pad "2" smd circle
			(at 0.40005 0 270)
			(size 0 0)
			(layers "F.Cu" "F.Mask" "F.Paste")
			(net "GND")
		)
	)
	(footprint ""
		(layer "F.Cu")
		(at 145.63344 -30.78734 -90)
		(property "Reference" "C6013"
			(at 0 0 270)
			(layer "F.SilkS")
			(hide yes)
			(effects
				(font
					(size 1.27 1.27)
				)
			)
		)
		(property "Value" ""
			(at 0 0 270)
			(layer "F.Fab")
			(effects
				(font
					(size 1.27 1.27)
				)
			)
		)
		(duplicate_pad_numbers_are_jumpers no)
		(fp_line
			(start -0.7874 0.4064)
			(end -0.7874 -0.4064)
			(stroke
				(width 0.1524)
				(type default)
			)
			(layer "F.SilkS")
		)
		(fp_line
			(start 0.7874 0.4064)
			(end -0.7874 0.4064)
			(stroke
				(width 0.1524)
				(type default)
			)
			(layer "F.SilkS")
		)
		(fp_line
			(start -0.7874 -0.4064)
			(end 0.7874 -0.4064)
			(stroke
				(width 0.1524)
				(type default)
			)
			(layer "F.SilkS")
		)
		(fp_line
			(start 0.7874 -0.4064)
			(end 0.7874 0.4064)
			(stroke
				(width 0.1524)
				(type default)
			)
			(layer "F.SilkS")
		)
		(fp_line
			(start -0.6858 0.3048)
			(end -0.6858 -0.3048)
			(stroke
				(width 0.1)
				(type default)
			)
			(layer "F.Fab")
		)
		(fp_line
			(start -0.1016 0.3048)
			(end -0.6858 0.3048)
			(stroke
				(width 0.1)
				(type default)
			)
			(layer "F.Fab")
		)
		(fp_line
			(start 0.1016 0.3048)
			(end 0.1016 0.2794)
			(stroke
				(width 0.1)
				(type default)
			)
			(layer "F.Fab")
		)
		(fp_line
			(start 0.6858 0.3048)
			(end 0.1016 0.3048)
			(stroke
				(width 0.1)
				(type default)
			)
			(layer "F.Fab")
		)
		(fp_line
			(start -0.1016 0.2794)
			(end -0.1016 0.3048)
			(stroke
				(width 0.1)
				(type default)
			)
			(layer "F.Fab")
		)
		(fp_line
			(start 0.1016 0.2794)
			(end -0.1016 0.2794)
			(stroke
				(width 0.1)
				(type default)
			)
			(layer "F.Fab")
		)
		(fp_line
			(start -0.1016 -0.2794)
			(end 0.1016 -0.2794)
			(stroke
				(width 0.1)
				(type default)
			)
			(layer "F.Fab")
		)
		(fp_line
			(start 0.1016 -0.2794)
			(end 0.1016 -0.3048)
			(stroke
				(width 0.1)
				(type default)
			)
			(layer "F.Fab")
		)
		(fp_line
			(start -0.6858 -0.3048)
			(end -0.1016 -0.3048)
			(stroke
				(width 0.1)
				(type default)
			)
			(layer "F.Fab")
		)
		(fp_line
			(start -0.1016 -0.3048)
			(end -0.1016 -0.2794)
			(stroke
				(width 0.1)
				(type default)
			)
			(layer "F.Fab")
		)
		(fp_line
			(start 0.1016 -0.3048)
			(end 0.6858 -0.3048)
			(stroke
				(width 0.1)
				(type default)
			)
			(layer "F.Fab")
		)
		(fp_line
			(start 0.6858 -0.3048)
			(end 0.6858 0.3048)
			(stroke
				(width 0.1)
				(type default)
			)
			(layer "F.Fab")
		)
		(pad "1" smd rect
			(at -0.40005 0 90)
			(size 0.4572 0.508)
			(layers "F.Cu" "F.Mask" "F.Paste")
			(net "USB3_CPU0_BMC_TX_DP")
		)
		(pad "2" smd rect
			(at 0.40005 0 90)
			(size 0.4572 0.508)
			(layers "F.Cu" "F.Mask" "F.Paste")
			(net "USB3_CPU0_BMC_TX_C2_DP")
		)
	)
)
